# T6G (Grand Teton) — schematic parts with pin connectivity, parts 4600–4614 of 8303; source: Cadence DE-HDL packaged netlist (pstxprt.dat, pstxnet.dat, pstchip.dat)

PU42  RAA229620GNPHA0  RAA229620GNP#HA0 IC  pkg QFN48_TH_0-4_6X6XH  page 193
  1  PWM0  OUT  = PVDDCR_SOC_P0_PWM1
  2  PWM1  OUT  = PVDDCR_SOC_P0_PWM2
  3  PWM2  OUT  = PVDDCR_SOC_P0_PWM3
  4  PWM3  OUT  = NC_PVDDCR_CPU0_P0_PWM9
  5  PWM4  OUT  = NC_PVDDCR_CPU0_P0_PWM8
  6  PWM5  OUT  = NC_PVDDCR_CPU0_P0_PWM7
  7  PWM6  OUT  = PVDDCR_CPU0_P0_PWM6
  8  PWM7  OUT  = PVDDCR_CPU0_P0_PWM5
  9  PWM8  OUT  = PVDDCR_CPU0_P0_PWM4
  10  PWM9  OUT  = PVDDCR_CPU0_P0_PWM3
  11  PWM10  OUT  = PVDDCR_CPU0_P0_PWM2
  12  PWM11  OUT  = PVDDCR_CPU0_P0_PWM1
  13  PMSDA  BI  = PVDDCR_CPU0_P0_PMSDA_R
  14  PMSCL  IN  = PVDDCR_CPU0_P0_PMSCL_R
  15  NPMALERT  OUT  = PVDDCR_CPU0_P0_PMALERT_R
  16  PG0  OUT  = PWRGD_PVDDCR_CPU0_P0_R
  17  EN0  IN  = PVDDCR_CPU0_P0_EN_R
  18  RESET_L  IN  = PVDDCR_CPU0_P0_RESET_N_R
  19  VDDIO  POWER  = PVDD18_S5_P0
  20  PG1  OUT  = PWRGD_PVDDCR_SOC_P0_R
  21  SVD  IN  = SVID_PVDDCR_CPU0_P0_SVD_R1
  22  SVC  IN  = SVID_PVDDCR_CPU0_P0_SVC_R1
  23  SVTO  OUT  = SVID_PVDDCR_CPU0_P0_SVTO_R
  24  SVTI  IN  = SVID_PVDDCR_CPU0_P0_SVTI_R
  25  VSEN0  IN  = VSENSE_PVDDCR_CPU0_P0_VSEN0
  26  RGND0  IN  = VSENSE_VSS_SENSE_A_P0
  27  CS11  IN  = PVDDCR_CPU0_P0_IMON1
  28  CS10  IN  = PVDDCR_CPU0_P0_IMON2
  29  CS9  IN  = PVDDCR_CPU0_P0_IMON3
  30  CS8  IN  = PVDDCR_CPU0_P0_IMON4
  31  CS7  IN  = PVDDCR_CPU0_P0_IMON5
  32  CS6  IN  = PVDDCR_CPU0_P0_IMON6
  33  CS5  IN  = NC_PVDDCR_CPU0_P0_IMON7
  34  CS4  IN  = NC_PVDDCR_CPU0_P0_IMON8
  35  CS3  IN  = NC_PVDDCR_CPU0_P0_IMON9
  36  CS2  IN  = PVDDCR_SOC_P0_IMON3
  37  CS1  IN  = PVDDCR_SOC_P0_IMON2
  38  CS0  IN  = PVDDCR_SOC_P0_IMON1
  39  RGND1  IN  = VSENSE_VSS_SENSE_A_P0
  40  VSEN1  IN  = VSENSE_PVDDCR_SOC_P0_VSEN1
  41  OCP_L  OUT  = PVDDCR_CPU0_P0_OCP_N_R
  42  \en1||addr_cfg\  IN  = PVDDCR_SOC_P0_EN//ADDR_CFG
  43  TEMP1  IN  = PVDDCR_SOC_P0_TEMP1
  44  TEMP0  IN  = PVDDCR_CPU0_P0_TEMP0
  45  \vmon||iinsen\  BI  = PVDDCR_CPU0_P0_VMON
  46  VINSEN  IN  = PVDDCR_CPU0_P0_VINSEN
  47  VCC  POWER  = PVDDCR_CPU0_P0_VCC
  48  VCCS  POWER  = PVDDCR_CPU0_P0_VCCS
  TH  TH_GND  POWER  = GND

PU43  ISL99390FRZTR5935  ISL99390FRZ-TR5935 IC  pkg QFN21_6X5XB  page 194
  1  VOS  IN  = PVDDCR_CPU0_P0_VOS2
  2  AGND  POWER  = GND
  3  VCC  POWER  = PVDDCR_CPU0_P0_VCC2
  4  PVCC  POWER  = PVDDCR_CPU0_P0_PVCC
  5  PGND1  POWER  = GND
  6  GL1  OUT  = NC_PVDDCR_CPU0_P0_GL1_2
  7_9-20_24  PGND2  POWER  = GND
  10_19  SW  OUT  = SW_PVDDCR_CPU0_P0_SW2
  25_29  VIN1  IN  = SW_P12V_AUX_PVDDCR_CPU0_P0_FLT
  30  VIN2  IN  = SW_P12V_AUX_PVDDCR_CPU0_P0_FLT
  31  DNC  TRI  = NC_PVDDCR_CPU0_P0_DNC2
  32  PHASE  POWER  = SW_PVDDCR_CPU0_P0_PH2
  33  BOOT  POWER  = SW_PVDDCR_CPU0_P0_BOOT2
  34  PWM  IN  = PVDDCR_CPU0_P0_PWM2
  35  EN  IN  = PVDDCR_CPU0_P0_VCC2
  36  TOUT_FLT  OUT  = PVDDCR_CPU0_P0_TEMP0
  37  LSET  OUT  = PVDDCR_CPU0_P0_LSET2
  38  IOUT  OUT  = PVDDCR_CPU0_P0_IMON2
  39  REFIN  IN  = PVDDCR_CPU0_P0_VCCS
  40  PGND3  POWER  = GND
  41  GL2  OUT  = NC_PVDDCR_CPU0_P0_GL2_2

PU44  ISL99390FRZTR5935  ISL99390FRZ-TR5935 IC  pkg QFN21_6X5XB  page 225
  1  VOS  IN  = PVDD11_S3_P1_VOS1
  2  AGND  POWER  = GND
  3  VCC  POWER  = PVDD11_S3_P1_VCC1
  4  PVCC  POWER  = PVDD11_S3_P1_PVCC
  5  PGND1  POWER  = GND
  6  GL1  OUT  = NC_PVDD11_S3_P1_GL1_1
  7_9-20_24  PGND2  POWER  = GND
  10_19  SW  OUT  = SW_PVDD11_S3_P1_SW1
  25_29  VIN1  IN  = SW_P12V_AUX_PVDD11_S3_P1_FLT
  30  VIN2  IN  = SW_P12V_AUX_PVDD11_S3_P1_FLT
  31  DNC  TRI  = NC_PVDD11_S3_P1_DNC1
  32  PHASE  POWER  = SW_PVDD11_S3_P1_PH1
  33  BOOT  POWER  = SW_PVDD11_S3_P1_BOOT1
  34  PWM  IN  = PVDD11_S3_P1_PWM1
  35  EN  IN  = PVDD11_S3_P1_VCC1
  36  TOUT_FLT  OUT  = PVDD11_S3_P1_TEMP0
  37  LSET  OUT  = PVDD11_S3_P1_LSET1
  38  IOUT  OUT  = PVDD11_S3_P1_IMON1
  39  REFIN  IN  = PVDD11_S3_P1_VCCS
  40  PGND3  POWER  = GND
  41  GL2  OUT  = NC_PVDD11_S3_P1_GL2_1

PU45  ISL99390FRZTR5935  ISL99390FRZ-TR5935 IC  pkg QFN21_6X5XB  page 225
  1  VOS  IN  = PVDD11_S3_P1_VOS2
  2  AGND  POWER  = GND
  3  VCC  POWER  = PVDD11_S3_P1_VCC2
  4  PVCC  POWER  = PVDD11_S3_P1_PVCC
  5  PGND1  POWER  = GND
  6  GL1  OUT  = NC_PVDD11_S3_P1_GL1_2
  7_9-20_24  PGND2  POWER  = GND
  10_19  SW  OUT  = SW_PVDD11_S3_P1_SW2
  25_29  VIN1  IN  = SW_P12V_AUX_PVDD11_S3_P1_FLT
  30  VIN2  IN  = SW_P12V_AUX_PVDD11_S3_P1_FLT
  31  DNC  TRI  = NC_PVDD11_S3_P1_DNC2
  32  PHASE  POWER  = SW_PVDD11_S3_P1_PH2
  33  BOOT  POWER  = SW_PVDD11_S3_P1_BOOT2
  34  PWM  IN  = PVDD11_S3_P1_PWM2
  35  EN  IN  = PVDD11_S3_P1_VCC2
  36  TOUT_FLT  OUT  = PVDD11_S3_P1_TEMP0
  37  LSET  OUT  = PVDD11_S3_P1_LSET2
  38  IOUT  OUT  = PVDD11_S3_P1_IMON2
  39  REFIN  IN  = PVDD11_S3_P1_VCCS
  40  PGND3  POWER  = GND
  41  GL2  OUT  = NC_PVDD11_S3_P1_GL2_2

PU46  ISL99390FRZTR5935  ISL99390FRZ-TR5935 IC  pkg QFN21_6X5XB  page 195
  1  VOS  IN  = PVDDCR_CPU0_P0_VOS3
  2  AGND  POWER  = GND
  3  VCC  POWER  = PVDDCR_CPU0_P0_VCC3
  4  PVCC  POWER  = PVDDCR_CPU0_P0_PVCC
  5  PGND1  POWER  = GND
  6  GL1  OUT  = NC_PVDDCR_CPU0_P0_GL1_3
  7_9-20_24  PGND2  POWER  = GND
  10_19  SW  OUT  = SW_PVDDCR_CPU0_P0_SW3
  25_29  VIN1  IN  = SW_P12V_AUX_PVDDCR_CPU0_P0_FLT
  30  VIN2  IN  = SW_P12V_AUX_PVDDCR_CPU0_P0_FLT
  31  DNC  TRI  = NC_PVDDCR_CPU0_P0_DNC3
  32  PHASE  POWER  = SW_PVDDCR_CPU0_P0_PH3
  33  BOOT  POWER  = SW_PVDDCR_CPU0_P0_BOOT3
  34  PWM  IN  = PVDDCR_CPU0_P0_PWM3
  35  EN  IN  = PVDDCR_CPU0_P0_VCC3
  36  TOUT_FLT  OUT  = PVDDCR_CPU0_P0_TEMP0
  37  LSET  OUT  = PVDDCR_CPU0_P0_LSET3
  38  IOUT  OUT  = PVDDCR_CPU0_P0_IMON3
  39  REFIN  IN  = PVDDCR_CPU0_P0_VCCS
  40  PGND3  POWER  = GND
  41  GL2  OUT  = NC_PVDDCR_CPU0_P0_GL2_3

PU47  ISL99390FRZTR5935  ISL99390FRZ-TR5935 IC  pkg QFN21_6X5XB  page 195
  1  VOS  IN  = PVDDCR_CPU0_P0_VOS4
  2  AGND  POWER  = GND
  3  VCC  POWER  = PVDDCR_CPU0_P0_VCC4
  4  PVCC  POWER  = PVDDCR_CPU0_P0_PVCC
  5  PGND1  POWER  = GND
  6  GL1  OUT  = NC_PVDDCR_CPU0_P0_GL1_4
  7_9-20_24  PGND2  POWER  = GND
  10_19  SW  OUT  = SW_PVDDCR_CPU0_P0_SW4
  25_29  VIN1  IN  = SW_P12V_AUX_PVDDCR_CPU0_P0_FLT
  30  VIN2  IN  = SW_P12V_AUX_PVDDCR_CPU0_P0_FLT
  31  DNC  TRI  = NC_PVDDCR_CPU0_P0_DNC4
  32  PHASE  POWER  = SW_PVDDCR_CPU0_P0_PH4
  33  BOOT  POWER  = SW_PVDDCR_CPU0_P0_BOOT4
  34  PWM  IN  = PVDDCR_CPU0_P0_PWM4
  35  EN  IN  = PVDDCR_CPU0_P0_VCC4
  36  TOUT_FLT  OUT  = PVDDCR_CPU0_P0_TEMP0
  37  LSET  OUT  = PVDDCR_CPU0_P0_LSET4
  38  IOUT  OUT  = PVDDCR_CPU0_P0_IMON4
  39  REFIN  IN  = PVDDCR_CPU0_P0_VCCS
  40  PGND3  POWER  = GND
  41  GL2  OUT  = NC_PVDDCR_CPU0_P0_GL2_4

PU48  ISL99390FRZTR5935  ISL99390FRZ-TR5935 IC  pkg QFN21_6X5XB  page 196
  1  VOS  IN  = PVDDCR_CPU0_P0_VOS5
  2  AGND  POWER  = GND
  3  VCC  POWER  = PVDDCR_CPU0_P0_VCC5
  4  PVCC  POWER  = PVDDCR_CPU0_P0_PVCC
  5  PGND1  POWER  = GND
  6  GL1  OUT  = NC_PVDDCR_CPU0_P0_GL1_5
  7_9-20_24  PGND2  POWER  = GND
  10_19  SW  OUT  = SW_PVDDCR_CPU0_P0_SW5
  25_29  VIN1  IN  = SW_P12V_AUX_PVDDCR_CPU0_P0_FLT
  30  VIN2  IN  = SW_P12V_AUX_PVDDCR_CPU0_P0_FLT
  31  DNC  TRI  = NC_PVDDCR_CPU0_P0_DNC5
  32  PHASE  POWER  = SW_PVDDCR_CPU0_P0_PH5
  33  BOOT  POWER  = SW_PVDDCR_CPU0_P0_BOOT5
  34  PWM  IN  = PVDDCR_CPU0_P0_PWM5
  35  EN  IN  = PVDDCR_CPU0_P0_VCC5
  36  TOUT_FLT  OUT  = PVDDCR_CPU0_P0_TEMP0
  37  LSET  OUT  = PVDDCR_CPU0_P0_LSET5
  38  IOUT  OUT  = PVDDCR_CPU0_P0_IMON5
  39  REFIN  IN  = PVDDCR_CPU0_P0_VCCS
  40  PGND3  POWER  = GND
  41  GL2  OUT  = NC_PVDDCR_CPU0_P0_GL2_5

PU49  ISL99390FRZTR5935  ISL99390FRZ-TR5935 IC  pkg QFN21_6X5XB  page 198
  1  VOS  IN  = PVDDCR_SOC_P0_VOS1
  2  AGND  POWER  = GND
  3  VCC  POWER  = PVDDCR_SOC_P0_VCC1
  4  PVCC  POWER  = PVDDCR_CPU0_P0_PVCC
  5  PGND1  POWER  = GND
  6  GL1  OUT  = NC_PVDDCR_SOC_P0_GL1_1
  7_9-20_24  PGND2  POWER  = GND
  10_19  SW  OUT  = SW_PVDDCR_SOC_P0_SW1
  25_29  VIN1  IN  = SW_P12V_AUX_PVDDCR_SOC_P0_FLT
  30  VIN2  IN  = SW_P12V_AUX_PVDDCR_SOC_P0_FLT
  31  DNC  TRI  = NC_PVDDCR_SOC_P0_DNC1
  32  PHASE  POWER  = SW_PVDDCR_SOC_P0_PH1
  33  BOOT  POWER  = SW_PVDDCR_SOC_P0_BOOT1
  34  PWM  IN  = PVDDCR_SOC_P0_PWM1
  35  EN  IN  = PVDDCR_SOC_P0_VCC1
  36  TOUT_FLT  OUT  = PVDDCR_SOC_P0_TEMP1
  37  LSET  OUT  = PVDDCR_SOC_P0_LSET1
  38  IOUT  OUT  = PVDDCR_SOC_P0_IMON1
  39  REFIN  IN  = PVDDCR_CPU0_P0_VCCS
  40  PGND3  POWER  = GND
  41  GL2  OUT  = NC_PVDDCR_SOC_P0_GL2_1

PU50  ISL99390FRZTR5935  ISL99390FRZ-TR5935 IC  pkg QFN21_6X5XB  page 198
  1  VOS  IN  = PVDDCR_SOC_P0_VOS2
  2  AGND  POWER  = GND
  3  VCC  POWER  = PVDDCR_SOC_P0_VCC2
  4  PVCC  POWER  = PVDDCR_CPU0_P0_PVCC
  5  PGND1  POWER  = GND
  6  GL1  OUT  = NC_PVDDCR_SOC_P0_GL1_2
  7_9-20_24  PGND2  POWER  = GND
  10_19  SW  OUT  = SW_PVDDCR_SOC_P0_SW2
  25_29  VIN1  IN  = SW_P12V_AUX_PVDDCR_SOC_P0_FLT
  30  VIN2  IN  = SW_P12V_AUX_PVDDCR_SOC_P0_FLT
  31  DNC  TRI  = NC_PVDDCR_SOC_P0_DNC2
  32  PHASE  POWER  = SW_PVDDCR_SOC_P0_PH2
  33  BOOT  POWER  = SW_PVDDCR_SOC_P0_BOOT2
  34  PWM  IN  = PVDDCR_SOC_P0_PWM2
  35  EN  IN  = PVDDCR_SOC_P0_VCC2
  36  TOUT_FLT  OUT  = PVDDCR_SOC_P0_TEMP1
  37  LSET  OUT  = PVDDCR_SOC_P0_LSET2
  38  IOUT  OUT  = PVDDCR_SOC_P0_IMON2
  39  REFIN  IN  = PVDDCR_CPU0_P0_VCCS
  40  PGND3  POWER  = GND
  41  GL2  OUT  = NC_PVDDCR_SOC_P0_GL2_2

PU51  ISL99390FRZTR5935  ISL99390FRZ-TR5935 IC  pkg QFN21_6X5XB  page 199
  1  VOS  IN  = PVDDCR_SOC_P0_VOS3
  2  AGND  POWER  = GND
  3  VCC  POWER  = PVDDCR_SOC_P0_VCC3
  4  PVCC  POWER  = PVDDCR_CPU0_P0_PVCC
  5  PGND1  POWER  = GND
  6  GL1  OUT  = NC_PVDDCR_SOC_P0_GL1_3
  7_9-20_24  PGND2  POWER  = GND
  10_19  SW  OUT  = SW_PVDDCR_SOC_P0_SW3
  25_29  VIN1  IN  = SW_P12V_AUX_PVDDCR_SOC_P0_FLT
  30  VIN2  IN  = SW_P12V_AUX_PVDDCR_SOC_P0_FLT
  31  DNC  TRI  = NC_PVDDCR_SOC_P0_DNC3
  32  PHASE  POWER  = SW_PVDDCR_SOC_P0_PH3
  33  BOOT  POWER  = SW_PVDDCR_SOC_P0_BOOT3
  34  PWM  IN  = PVDDCR_SOC_P0_PWM3
  35  EN  IN  = PVDDCR_SOC_P0_VCC3
  36  TOUT_FLT  OUT  = PVDDCR_SOC_P0_TEMP1
  37  LSET  OUT  = PVDDCR_SOC_P0_LSET3
  38  IOUT  OUT  = PVDDCR_SOC_P0_IMON3
  39  REFIN  IN  = PVDDCR_CPU0_P0_VCCS
  40  PGND3  POWER  = GND
  41  GL2  OUT  = NC_PVDDCR_SOC_P0_GL2_3

PU52  ISL99390FRZTR5935  ISL99390FRZ-TR5935 IC  pkg QFN21_6X5XB  page 223
  1  VOS  IN  = PVDDIO_P1_VOS3
  2  AGND  POWER  = GND
  3  VCC  POWER  = PVDDIO_P1_VCC3
  4  PVCC  POWER  = PVDDCR_CPU1_P1_PVCC
  5  PGND1  POWER  = GND
  6  GL1  OUT  = NC_PVDDIO_P1_GL1_3
  7_9-20_24  PGND2  POWER  = GND
  10_19  SW  OUT  = SW_PVDDIO_P1_SW3
  25_29  VIN1  IN  = SW_P12V_AUX_PVDDIO_P1_FLT
  30  VIN2  IN  = SW_P12V_AUX_PVDDIO_P1_FLT
  31  DNC  TRI  = NC_PVDDIO_P1_DNC3
  32  PHASE  POWER  = SW_PVDDIO_P1_BOOTR3
  33  BOOT  POWER  = SW_PVDDIO_P1_BOOT3
  34  PWM  IN  = PVDDIO_P1_PWM3
  35  EN  IN  = PVDDIO_P1_VCC3
  36  TOUT_FLT  OUT  = PVDDIO_P1_TEMP1
  37  LSET  OUT  = PVDDIO_P1_LSET3
  38  IOUT  OUT  = PVDDIO_P1_IMON3
  39  REFIN  IN  = PVDDCR_CPU1_P1_VCCS
  40  PGND3  POWER  = GND
  41  GL2  OUT  = NC_PVDDIO_P1_GL2_3

PU53  ISL99390FRZTR5935  ISL99390FRZ-TR5935 IC  pkg QFN21_6X5XB  page 223
  1  VOS  IN  = PVDDIO_P1_VOS4
  2  AGND  POWER  = GND
  3  VCC  POWER  = PVDDIO_P1_VCC4
  4  PVCC  POWER  = PVDDCR_CPU1_P1_PVCC
  5  PGND1  POWER  = GND
  6  GL1  OUT  = NC_PVDDIO_P1_GL1_4
  7_9-20_24  PGND2  POWER  = GND
  10_19  SW  OUT  = SW_PVDDIO_P1_SW4
  25_29  VIN1  IN  = SW_P12V_AUX_PVDDIO_P1_FLT
  30  VIN2  IN  = SW_P12V_AUX_PVDDIO_P1_FLT
  31  DNC  TRI  = NC_PVDDIO_P1_DNC4
  32  PHASE  POWER  = SW_PVDDIO_P1_BOOTR4
  33  BOOT  POWER  = SW_PVDDIO_P1_BOOT4
  34  PWM  IN  = PVDDIO_P1_PWM4
  35  EN  IN  = PVDDIO_P1_VCC4
  36  TOUT_FLT  OUT  = PVDDIO_P1_TEMP1
  37  LSET  OUT  = PVDDIO_P1_LSET4
  38  IOUT  OUT  = PVDDIO_P1_IMON4
  39  REFIN  IN  = PVDDCR_CPU1_P1_VCCS
  40  PGND3  POWER  = GND
  41  GL2  OUT  = NC_PVDDIO_P1_GL2_4

PU54  RAA229621GNPHA0  RAA229621GNP#HA0 IC  pkg QFN40_TH_0-4_5X5XE  page 224
  1  PWM0  OUT  = NC_PVDD11_S3_P1_PWM8
  2  PWM1  OUT  = NC_PVDD11_S3_P1_PWM7
  3  PWM2  OUT  = NC_PVDD11_S3_P1_PWM6
  4  PWM3  OUT  = NC_PVDD11_S3_P1_PWM5
  5  PWM4  OUT  = NC_PVDD11_S3_P1_PWM4
  6  PWM5  OUT  = NC_PVDD11_S3_P1_PWM3
  7  PWM6  OUT  = PVDD11_S3_P1_PWM2
  8  PWM7  OUT  = PVDD11_S3_P1_PWM1
  9  PMSDA  BI  = PVDD11_S3_P1_PMSDA_R
  10  PMSCL  IN  = PVDD11_S3_P1_PMSCL_R
  11  NPMALERT  OUT  = PVDD11_S3_P1_PMALERT_R
  12  PG0  OUT  = PWRGD_PVDD11_S3_P1_R
  13  EN0  IN  = PVDD11_S3_P1_EN_R
  14  RESET_L  IN  = PVDD11_S3_P1_RESET_N_R
  15  VDDIO  IN  = PVDD11_S3_P1_VDDIO
  16  PG1  OUT  = NC_PVDD11_S3_P1_PG1
  17  SVD  BI  = GND
  18  SVC  IN  = GND
  19  SVTO  OUT  = NC_PVDD11_S3_P1_SVTO
  20  SVTI  IN  = GND
  21  VSEN0  IN  = VSENSE_PVDD11_S3_P1_R
  22  RGND0  IN  = VSENSE_VSS_SENSE_C_P1
  23  CS7  IN  = PVDD11_S3_P1_IMON1
  24  CS6  IN  = PVDD11_S3_P1_IMON2
  25  CS5  IN  = NC_PVDD11_S3_P1_IMON3
  26  CS4  IN  = NC_PVDD11_S3_P1_IMON4
  27  CS3  IN  = NC_PVDD11_S3_P1_IMON5
  28  CS2  IN  = NC_PVDD11_S3_P1_IMON6
  29  CS1  IN  = NC_PVDD11_S3_P1_IMON7
  30  CS0  IN  = NC_PVDD11_S3_P1_IMON8
  31  RGND1  IN  = GND
  32  VSEN1  IN  = GND
  33  OCP_L  OUT  = PVDD11_S3_P1_OCP_N_R
  34  \en1||addr_cfg\  IN  = PVDD11_S3_P1_ADDR_CFG
  35  TEMP1  IN  = PVDD11_S3_P1_TEMP1
  36  TEMP0  IN  = PVDD11_S3_P1_TEMP0
  37  \vmon||iinsen\  IN  = PVDD11_S3_P1_VMON
  38  VINSEN  IN  = PVDD11_S3_P1_VINSEN
  39  VCC  POWER  = PVDD11_S3_P1_VCC
  40  VCCS  POWER  = PVDD11_S3_P1_VCCS
  TH  TH_GND  POWER  = GND

PU55  MPQ8633AGLEC807Z  MPQ8633AGLE-C807-Z IC  pkg QFN14_4X3  page 192
  1  BST  IN  = SW_PVDD_33_S5_BST
  2  AGND  POWER  = GND
  3  CS  IN  = PVDD_33_S5_CS
  4  MODE  IN  = PVDD_33_S5_MODE
  5  TRK_REF  IN  = PVDD_33_S5_REF
  6  RGND  POWER  = GND
  7  FB  IN  = PVDD_33_S5_FB
  8  EN  IN  = PVDD33_S5_EN
  9  PGOOD  OUT  = PWRGD_PVDD33_S5
  10  VIN1  IN  = SW_P12V_AUX_PVDD_33_S5_FLT
  11_18  PGND  POWER  = GND
  19  VCC  POWER  = PVDD_33_S5_VCC
  20  SW  OUT  = SW_PVDD_33_S5_SW
  21  VIN2  IN  = SW_P12V_AUX_PVDD_33_S5_FLT

PU57  MPQ8633BGLEC838Z  MPQ8633BGLE-C838-Z IC  pkg QFN14_4X3  page 209
  1  BST  IN  = SW_PVDD18_S5_P0_BST
  2  AGND  POWER  = GND
  3  CS  IN  = PVDD18_S5_P0_CS
  4  MODE  IN  = PVDD18_S5_P0_MODE
  5  TRK_REF  IN  = PVDD18_S5_P0_REF
  6  RGND  POWER  = PVDD18_S5_P0_RGND
  7  FB  IN  = PVDD18_S5_P0_FB
  8  EN  IN  = PVDD18_S5_P0_EN
  9  PGOOD  OUT  = PWRGD_PVDD18_S5_P0
  10  VIN1  IN  = SW_P12V_AUX_PVDD18_S5_P0_FLT
  11_18  PGND  POWER  = GND
  19  VCC  IN  = PVDD18_S5_P0_VCC
  20  SW  OUT  = SW_PVDD18_S5_P0_SW
  21  VIN2  IN  = SW_P12V_AUX_PVDD18_S5_P0_FLT
